#ISCELL
  mstr_misc prelim *
  *
#ISCELL
  mstr_symbols design_note *
  *
#ISCELL
  mstr_symbols intel_corp_bpage *
  *
#ISCELL
  mstr_standard offpage *
  page61_i1
#ISCELL
  mstr_standard tap *
  page61_i10
#ISCELL
  mstr_standard tap *
  page61_i100
#ISCELL
  mstr_standard tap *
  page61_i101
#ISCELL
  mstr_standard tap *
  page61_i102
#ISCELL
  mstr_standard tap *
  page61_i103
#ISCELL
  mstr_standard tap *
  page61_i104
#ISCELL
  mstr_standard tap *
  page61_i105
#ISCELL
  mstr_standard tap *
  page61_i106
#ISCELL
  mstr_standard tap *
  page61_i107
#ISCELL
  mstr_standard tap *
  page61_i108
#ISCELL
  mstr_standard tap *
  page61_i109
#ISCELL
  mstr_standard tap *
  page61_i11
#ISCELL
  mstr_standard tap *
  page61_i110
#ISCELL
  mstr_standard tap *
  page61_i111
#ISCELL
  mstr_standard tap *
  page61_i112
#ISCELL
  mstr_standard tap *
  page61_i113
#ISCELL
  mstr_standard tap *
  page61_i114
#ISCELL
  mstr_standard tap *
  page61_i115
#ISCELL
  mstr_standard tap *
  page61_i116
#ISCELL
  mstr_standard tap *
  page61_i117
#ISCELL
  mstr_standard tap *
  page61_i118
#ISCELL
  mstr_standard tap *
  page61_i119
#ISCELL
  mstr_standard tap *
  page61_i12
#ISCELL
  mstr_standard tap *
  page61_i120
#ISCELL
  mstr_standard tap *
  page61_i121
#ISCELL
  mstr_standard tap *
  page61_i122
#ISCELL
  mstr_standard tap *
  page61_i123
#ISCELL
  mstr_standard tap *
  page61_i124
#ISCELL
  mstr_standard tap *
  page61_i125
#ISCELL
  mstr_standard tap *
  page61_i126
#ISCELL
  mstr_standard tap *
  page61_i127
#ISCELL
  mstr_standard tap *
  page61_i128
#ISCELL
  mstr_standard tap *
  page61_i129
#ISCELL
  mstr_standard tap *
  page61_i13
#ISCELL
  mstr_standard tap *
  page61_i130
#ISCELL
  mstr_standard tap *
  page61_i131
#ISCELL
  mstr_standard tap *
  page61_i132
#ISCELL
  mstr_standard tap *
  page61_i133
#ISCELL
  mstr_standard tap *
  page61_i134
#ISCELL
  mstr_standard tap *
  page61_i135
#ISCELL
  mstr_standard tap *
  page61_i136
#ISCELL
  mstr_standard tap *
  page61_i137
#ISCELL
  mstr_standard tap *
  page61_i138
#ISCELL
  mstr_standard tap *
  page61_i139
#ISCELL
  mstr_standard tap *
  page61_i14
#ISCELL
  mstr_standard tap *
  page61_i140
#ISCELL
  mstr_standard tap *
  page61_i141
#ISCELL
  mstr_standard tap *
  page61_i142
#ISCELL
  mstr_standard tap *
  page61_i143
#ISCELL
  mstr_standard tap *
  page61_i144
#ISCELL
  mstr_standard tap *
  page61_i145
#ISCELL
  mstr_standard tap *
  page61_i146
#ISCELL
  mstr_standard offpage *
  page61_i147
#ISCELL
  mstr_standard offpage *
  page61_i148
#ISCELL
  mstr_standard offpage *
  page61_i149
#ISCELL
  mstr_standard tap *
  page61_i15
#ISCELL
  mstr_standard offpage *
  page61_i150
#ISCELL
  mstr_standard offpage *
  page61_i151
#ISCELL
  mstr_standard offpage *
  page61_i152
#ISCELL
  mstr_standard offpage *
  page61_i153
#ISCELL
  mstr_standard offpage *
  page61_i154
#ISCELL
  mstr_standard offpage *
  page61_i155
#ISCELL
  mstr_standard offpage *
  page61_i156
#ISCELL
  mstr_standard tap *
  page61_i157
#ISCELL
  mstr_standard tap *
  page61_i158
#ISCELL
  mstr_standard tap *
  page61_i159
#ISCELL
  mstr_standard tap *
  page61_i16
#ISCELL
  mstr_standard tap *
  page61_i160
#ISCELL
  mstr_standard tap *
  page61_i161
#ISCELL
  mstr_standard tap *
  page61_i162
#ISCELL
  mstr_standard tap *
  page61_i163
#ISCELL
  mstr_standard tap *
  page61_i164
#ISCELL
  mstr_standard tap *
  page61_i165
#ISCELL
  mstr_standard tap *
  page61_i166
#ISCELL
  mstr_standard tap *
  page61_i167
#ISCELL
  mstr_standard tap *
  page61_i168
#ISCELL
  mstr_standard tap *
  page61_i169
#ISCELL
  mstr_standard tap *
  page61_i17
#ISCELL
  mstr_standard tap *
  page61_i170
#ISCELL
  mstr_standard offpage *
  page61_i171
#CELL
  chpset_lib skx_ext_b *
  page61_i172
#ISCELL
  mstr_standard tap *
  page61_i18
#ISCELL
  mstr_standard tap *
  page61_i19
#ISCELL
  mstr_standard offpage *
  page61_i2
#ISCELL
  mstr_standard tap *
  page61_i20
#ISCELL
  mstr_standard tap *
  page61_i21
#ISCELL
  mstr_standard tap *
  page61_i22
#ISCELL
  mstr_standard tap *
  page61_i23
#ISCELL
  mstr_standard tap *
  page61_i24
#ISCELL
  mstr_standard tap *
  page61_i25
#ISCELL
  mstr_standard tap *
  page61_i26
#ISCELL
  mstr_standard tap *
  page61_i27
#ISCELL
  mstr_standard tap *
  page61_i28
#ISCELL
  mstr_standard tap *
  page61_i29
#ISCELL
  mstr_standard offpage *
  page61_i3
#ISCELL
  mstr_standard tap *
  page61_i31
#ISCELL
  mstr_standard tap *
  page61_i32
#ISCELL
  mstr_standard tap *
  page61_i33
#ISCELL
  mstr_standard tap *
  page61_i34
#ISCELL
  mstr_standard tap *
  page61_i35
#ISCELL
  mstr_standard tap *
  page61_i36
#ISCELL
  mstr_standard tap *
  page61_i37
#ISCELL
  mstr_standard tap *
  page61_i38
#ISCELL
  mstr_standard tap *
  page61_i39
#ISCELL
  mstr_standard offpage *
  page61_i4
#ISCELL
  mstr_standard tap *
  page61_i40
#ISCELL
  mstr_standard tap *
  page61_i41
#ISCELL
  mstr_standard tap *
  page61_i42
#ISCELL
  mstr_standard tap *
  page61_i43
#ISCELL
  mstr_standard tap *
  page61_i44
#ISCELL
  mstr_standard tap *
  page61_i45
#ISCELL
  mstr_standard tap *
  page61_i46
#ISCELL
  mstr_standard tap *
  page61_i47
#ISCELL
  mstr_standard tap *
  page61_i48
#ISCELL
  mstr_standard tap *
  page61_i49
#ISCELL
  mstr_standard tap *
  page61_i5
#ISCELL
  mstr_standard tap *
  page61_i50
#ISCELL
  mstr_standard tap *
  page61_i51
#ISCELL
  mstr_standard tap *
  page61_i52
#ISCELL
  mstr_standard tap *
  page61_i53
#ISCELL
  mstr_standard tap *
  page61_i54
#ISCELL
  mstr_standard tap *
  page61_i55
#ISCELL
  mstr_standard tap *
  page61_i56
#ISCELL
  mstr_standard tap *
  page61_i57
#ISCELL
  mstr_standard tap *
  page61_i58
#ISCELL
  mstr_standard tap *
  page61_i59
#ISCELL
  mstr_standard tap *
  page61_i6
#ISCELL
  mstr_standard tap *
  page61_i60
#ISCELL
  mstr_standard tap *
  page61_i61
#ISCELL
  mstr_standard tap *
  page61_i62
#ISCELL
  mstr_standard tap *
  page61_i63
#ISCELL
  mstr_standard tap *
  page61_i64
#ISCELL
  mstr_standard tap *
  page61_i65
#ISCELL
  mstr_standard tap *
  page61_i66
#ISCELL
  mstr_standard tap *
  page61_i67
#ISCELL
  mstr_standard tap *
  page61_i68
#ISCELL
  mstr_standard tap *
  page61_i69
#ISCELL
  mstr_standard tap *
  page61_i7
#ISCELL
  mstr_standard tap *
  page61_i70
#ISCELL
  mstr_standard tap *
  page61_i71
#ISCELL
  mstr_standard offpage *
  page61_i72
#ISCELL
  mstr_standard tap *
  page61_i73
#ISCELL
  mstr_standard tap *
  page61_i74
#ISCELL
  mstr_standard tap *
  page61_i75
#ISCELL
  mstr_standard tap *
  page61_i76
#ISCELL
  mstr_standard tap *
  page61_i77
#ISCELL
  mstr_standard tap *
  page61_i78
#ISCELL
  mstr_standard tap *
  page61_i79
#ISCELL
  mstr_standard tap *
  page61_i8
#ISCELL
  mstr_standard tap *
  page61_i80
#ISCELL
  mstr_standard tap *
  page61_i81
#ISCELL
  mstr_standard tap *
  page61_i82
#ISCELL
  mstr_standard tap *
  page61_i83
#ISCELL
  mstr_standard tap *
  page61_i84
#ISCELL
  mstr_standard tap *
  page61_i85
#ISCELL
  mstr_standard tap *
  page61_i86
#ISCELL
  mstr_standard tap *
  page61_i87
#ISCELL
  mstr_standard tap *
  page61_i88
#ISCELL
  mstr_standard tap *
  page61_i89
#ISCELL
  mstr_standard tap *
  page61_i9
#ISCELL
  mstr_standard tap *
  page61_i90
#ISCELL
  mstr_standard tap *
  page61_i91
#ISCELL
  mstr_standard tap *
  page61_i92
#ISCELL
  mstr_standard tap *
  page61_i93
#ISCELL
  mstr_standard tap *
  page61_i94
#ISCELL
  mstr_standard tap *
  page61_i95
#ISCELL
  mstr_standard tap *
  page61_i96
#ISCELL
  mstr_standard tap *
  page61_i97
#ISCELL
  mstr_standard tap *
  page61_i98
#ISCELL
  mstr_standard tap *
  page61_i99
